(kicad_pcb
	(version 20260206)
	(generator "pcbnew")
	(generator_version "10.0")
	(general
		(thickness 1.6)
		(legacy_teardrops no)
	)
	(paper "A4")
	(title_block
		(title "Wiwynn_Tioga_Pass_MB.brd")
		(comment 1 "Tioga Pass / footprints 3056-3062 of 4770")
	)
	(layers
		(0 "F.Cu" signal "TOP")
		(4 "In1.Cu" signal "L2GND")
		(6 "In2.Cu" signal "L3")
		(8 "In3.Cu" signal "L4GND")
		(10 "In4.Cu" signal "L5")
		(12 "In5.Cu" signal "L6GND")
		(14 "In6.Cu" signal "L7VCC")
		(16 "In7.Cu" signal "L8VCC")
		(18 "In8.Cu" signal "L9GND")
		(20 "In9.Cu" signal "L10")
		(22 "In10.Cu" signal "L11GND")
		(24 "In11.Cu" signal "L12")
		(26 "In12.Cu" signal "L13GND")
		(2 "B.Cu" signal "BOTTOM")
		(9 "F.Adhes" user "F.Adhesive")
		(11 "B.Adhes" user "B.Adhesive")
		(13 "F.Paste" user "Package Geometry/Pastemask Top")
		(15 "B.Paste" user "Package Geometry/Pastemask Bottom")
		(5 "F.SilkS" user "Ref Des/Silkscreen Top")
		(7 "B.SilkS" user "Ref Des/Silkscreen Bottom")
		(1 "F.Mask" user "Board Geometry/Soldermask Top")
		(3 "B.Mask" user "Board Geometry/Soldermask Bottom")
		(17 "Dwgs.User" user "User.Drawings")
		(19 "Cmts.User" user "User.Comments")
		(21 "Eco1.User" user "User.Eco1")
		(23 "Eco2.User" user "User.Eco2")
		(25 "Edge.Cuts" user "Board Geometry/Outline")
		(27 "Margin" user)
		(31 "F.CrtYd" user "Package Geometry/Place Bound Top")
		(29 "B.CrtYd" user "Package Geometry/Place Bound Bottom")
		(35 "F.Fab" user "Ref Des/Assembly Top")
		(33 "B.Fab" user "Ref Des/Assembly Bottom")
	)
	(footprint ""
		(layer "B.Cu")
		(at 484.6574 -39.5986 180)
		(property "Reference" "C1T5"
			(at 0 0 0)
			(layer "B.SilkS")
			(hide yes)
			(effects
				(font
					(size 1.27 1.27)
				)
				(justify mirror)
			)
		)
		(property "Value" ""
			(at 0 0 0)
			(layer "B.Fab")
			(effects
				(font
					(size 1.27 1.27)
				)
				(justify mirror)
			)
		)
		(duplicate_pad_numbers_are_jumpers no)
		(fp_poly
			(pts
				(xy -0.3048 -0.1016) (xy -0.3048 0.9906) (xy 0.3048 0.9906) (xy 0.3048 -0.1016)
			)
			(stroke
				(width 0)
				(type default)
			)
			(fill no)
			(layer "B.CrtYd")
		)
		(fp_line
			(start 0.3048 0.9906)
			(end -0.3048 0.9906)
			(stroke
				(width 0.1)
				(type default)
			)
			(layer "B.Fab")
		)
		(fp_line
			(start 0.3048 -0.1016)
			(end 0.3048 0.9906)
			(stroke
				(width 0.1)
				(type default)
			)
			(layer "B.Fab")
		)
		(fp_line
			(start -0.3048 0.9906)
			(end -0.3048 -0.1016)
			(stroke
				(width 0.1)
				(type default)
			)
			(layer "B.Fab")
		)
		(fp_line
			(start -0.3048 -0.1016)
			(end 0.3048 -0.1016)
			(stroke
				(width 0.1)
				(type default)
			)
			(layer "B.Fab")
		)
		(pad "1" smd rect
			(at 0 0)
			(size 0.508 0.508)
			(layers "B.Cu" "B.Mask" "B.Paste")
			(net "P0V9_LAN")
		)
		(pad "2" smd rect
			(at 0 0.889)
			(size 0.508 0.508)
			(layers "B.Cu" "B.Mask" "B.Paste")
			(net "GND")
		)
		(zone
			(layer "B.Cu")
			(hatch none 0.5)
			(connect_pads
				(clearance 0)
			)
			(min_thickness 0.25)
			(keepout
				(tracks not_allowed)
				(vias allowed)
				(pads allowed)
				(copperpour not_allowed)
				(footprints allowed)
			)
			(placement
				(enabled no)
				(sheetname "")
			)
			(fill
				(thermal_gap 0.5)
				(thermal_bridge_width 0.5)
				(island_removal_mode 0)
			)
			(polygon
				(pts
					(xy 484.4034 -40.2336) (xy 484.9114 -40.2336) (xy 484.9114 -39.8526) (xy 484.4034 -39.8526)
				)
			)
		)
		(zone
			(layer "B.Cu")
			(hatch none 0.5)
			(connect_pads
				(clearance 0)
			)
			(min_thickness 0.25)
			(keepout
				(tracks allowed)
				(vias not_allowed)
				(pads allowed)
				(copperpour not_allowed)
				(footprints allowed)
			)
			(placement
				(enabled no)
				(sheetname "")
			)
			(fill
				(thermal_gap 0.5)
				(thermal_bridge_width 0.5)
				(island_removal_mode 0)
			)
			(polygon
				(pts
					(xy 484.4034 -39.8526) (xy 484.9114 -39.8526) (xy 484.9114 -40.2336) (xy 484.4034 -40.2336)
				)
			)
		)
	)
	(footprint ""
		(layer "B.Cu")
		(at 472.2368 -124.079 90)
		(property "Reference" "R1M6"
			(at 0 0 90)
			(layer "B.SilkS")
			(hide yes)
			(effects
				(font
					(size 1.27 1.27)
				)
				(justify mirror)
			)
		)
		(property "Value" ""
			(at 0 0 90)
			(layer "B.Fab")
			(effects
				(font
					(size 1.27 1.27)
				)
				(justify mirror)
			)
		)
		(duplicate_pad_numbers_are_jumpers no)
		(fp_rect
			(start -0.2794 -0.1016)
			(end 0.2794 0.9906)
			(stroke
				(width 0)
				(type default)
			)
			(fill no)
			(layer "B.CrtYd")
		)
		(fp_line
			(start 0.2794 -0.1016)
			(end 0.2794 0.9906)
			(stroke
				(width 0.1)
				(type default)
			)
			(layer "B.Fab")
		)
		(fp_line
			(start -0.2794 -0.1016)
			(end 0.2794 -0.1016)
			(stroke
				(width 0.1)
				(type default)
			)
			(layer "B.Fab")
		)
		(fp_line
			(start 0.2794 0.9906)
			(end -0.2794 0.9906)
			(stroke
				(width 0.1)
				(type default)
			)
			(layer "B.Fab")
		)
		(fp_line
			(start -0.2794 0.9906)
			(end -0.2794 -0.1016)
			(stroke
				(width 0.1)
				(type default)
			)
			(layer "B.Fab")
		)
		(pad "1" smd rect
			(at 0 0 270)
			(size 0.508 0.508)
			(layers "B.Cu" "B.Mask" "B.Paste")
			(net "USB2_P01_DN")
		)
		(pad "2" smd rect
			(at 0 0.889 270)
			(size 0.508 0.508)
			(layers "B.Cu" "B.Mask" "B.Paste")
			(net "USB2_P01_ESD_DN")
		)
		(zone
			(layer "B.Cu")
			(hatch none 0.5)
			(connect_pads
				(clearance 0)
			)
			(min_thickness 0.25)
			(keepout
				(tracks allowed)
				(vias not_allowed)
				(pads allowed)
				(copperpour not_allowed)
				(footprints allowed)
			)
			(placement
				(enabled no)
				(sheetname "")
			)
			(fill
				(thermal_gap 0.5)
				(thermal_bridge_width 0.5)
				(island_removal_mode 0)
			)
			(polygon
				(pts
					(xy 472.4908 -123.825) (xy 472.8718 -123.825) (xy 472.8718 -124.333) (xy 472.4908 -124.333)
				)
			)
		)
		(zone
			(layer "B.Cu")
			(hatch none 0.5)
			(connect_pads
				(clearance 0)
			)
			(min_thickness 0.25)
			(keepout
				(tracks not_allowed)
				(vias allowed)
				(pads allowed)
				(copperpour not_allowed)
				(footprints allowed)
			)
			(placement
				(enabled no)
				(sheetname "")
			)
			(fill
				(thermal_gap 0.5)
				(thermal_bridge_width 0.5)
				(island_removal_mode 0)
			)
			(polygon
				(pts
					(xy 472.4908 -123.825) (xy 472.8718 -123.825) (xy 472.8718 -124.333) (xy 472.4908 -124.333)
				)
			)
		)
	)
	(footprint ""
		(layer "B.Cu")
		(at 24.765 -30.099 -90)
		(property "Reference" "R9T6"
			(at 0 0 90)
			(layer "B.SilkS")
			(hide yes)
			(effects
				(font
					(size 1.27 1.27)
				)
				(justify mirror)
			)
		)
		(property "Value" ""
			(at 0 0 90)
			(layer "B.Fab")
			(effects
				(font
					(size 1.27 1.27)
				)
				(justify mirror)
			)
		)
		(duplicate_pad_numbers_are_jumpers no)
		(fp_rect
			(start 0.2794 0.9906)
			(end -0.2794 -0.1016)
			(stroke
				(width 0)
				(type default)
			)
			(fill no)
			(layer "B.CrtYd")
		)
		(fp_line
			(start -0.2794 0.9906)
			(end -0.2794 -0.1016)
			(stroke
				(width 0.1)
				(type default)
			)
			(layer "B.Fab")
		)
		(fp_line
			(start 0.2794 0.9906)
			(end -0.2794 0.9906)
			(stroke
				(width 0.1)
				(type default)
			)
			(layer "B.Fab")
		)
		(fp_line
			(start -0.2794 -0.1016)
			(end 0.2794 -0.1016)
			(stroke
				(width 0.1)
				(type default)
			)
			(layer "B.Fab")
		)
		(fp_line
			(start 0.2794 -0.1016)
			(end 0.2794 0.9906)
			(stroke
				(width 0.1)
				(type default)
			)
			(layer "B.Fab")
		)
		(pad "1" smd rect
			(at 0 0 90)
			(size 0.508 0.508)
			(layers "B.Cu" "B.Mask" "B.Paste")
			(net "P12V_PSU")
		)
		(pad "2" smd rect
			(at 0 0.889 90)
			(size 0.508 0.508)
			(layers "B.Cu" "B.Mask" "B.Paste")
			(net "FM_P12V_HOTSWAP0_EN")
		)
		(zone
			(layer "B.Cu")
			(hatch none 0.5)
			(connect_pads
				(clearance 0)
			)
			(min_thickness 0.25)
			(keepout
				(tracks not_allowed)
				(vias allowed)
				(pads allowed)
				(copperpour not_allowed)
				(footprints allowed)
			)
			(placement
				(enabled no)
				(sheetname "")
			)
			(fill
				(thermal_gap 0.5)
				(thermal_bridge_width 0.5)
				(island_removal_mode 0)
			)
			(polygon
				(pts
					(xy 24.13 -29.845) (xy 24.511 -29.845) (xy 24.511 -30.353) (xy 24.13 -30.353)
				)
			)
		)
		(zone
			(layer "B.Cu")
			(hatch none 0.5)
			(connect_pads
				(clearance 0)
			)
			(min_thickness 0.25)
			(keepout
				(tracks allowed)
				(vias not_allowed)
				(pads allowed)
				(copperpour not_allowed)
				(footprints allowed)
			)
			(placement
				(enabled no)
				(sheetname "")
			)
			(fill
				(thermal_gap 0.5)
				(thermal_bridge_width 0.5)
				(island_removal_mode 0)
			)
			(polygon
				(pts
					(xy 24.13 -29.845) (xy 24.511 -29.845) (xy 24.511 -30.353) (xy 24.13 -30.353)
				)
			)
		)
	)
	(footprint ""
		(layer "B.Cu")
		(at 368.346228 -70.696074)
		(property "Reference" "C2R3"
			(at 0 0 0)
			(layer "B.SilkS")
			(hide yes)
			(effects
				(font
					(size 1.27 1.27)
				)
				(justify mirror)
			)
		)
		(property "Value" ""
			(at 0 0 0)
			(layer "B.Fab")
			(effects
				(font
					(size 1.27 1.27)
				)
				(justify mirror)
			)
		)
		(duplicate_pad_numbers_are_jumpers no)
		(fp_rect
			(start 0.2794 0.9144)
			(end -0.2794 -0.1143)
			(stroke
				(width 0)
				(type default)
			)
			(fill no)
			(layer "B.CrtYd")
		)
		(fp_line
			(start -0.2794 -0.1143)
			(end -0.2794 0.9144)
			(stroke
				(width 0.1)
				(type default)
			)
			(layer "B.Fab")
		)
		(fp_line
			(start -0.2794 0.9144)
			(end 0.2794 0.9144)
			(stroke
				(width 0.1)
				(type default)
			)
			(layer "B.Fab")
		)
		(fp_line
			(start 0.2794 -0.1143)
			(end -0.2794 -0.1143)
			(stroke
				(width 0.1)
				(type default)
			)
			(layer "B.Fab")
		)
		(fp_line
			(start 0.2794 0.9144)
			(end 0.2794 -0.1143)
			(stroke
				(width 0.1)
				(type default)
			)
			(layer "B.Fab")
		)
		(pad "1" smd custom
			(at 0 0 270)
			(size 0.10414 0.10414)
			(layers "B.Cu" "B.Mask" "B.Paste")
			(net "P3V3_STBY")
			(options
				(clearance outline)
				(anchor circle)
			)
			(primitives
				(gr_poly
					(pts
						(xy -0.20828 -0.08636) (xy -0.20828 0.08636) (xy -0.08636 0.20828) (xy 0.086614 0.20828) (xy 0.20828 0.086614)
						(xy 0.20828 -0.08636) (xy 0.08636 -0.20828) (xy -0.08636 -0.20828)
					)
					(width 0)
					(fill yes)
				)
			)
		)
		(pad "2" smd custom
			(at 0 0.8001 270)
			(size 0.10414 0.10414)
			(layers "B.Cu" "B.Mask" "B.Paste")
			(net "GND")
			(options
				(clearance outline)
				(anchor circle)
			)
			(primitives
				(gr_poly
					(pts
						(xy -0.20828 -0.08636) (xy -0.20828 0.08636) (xy -0.08636 0.20828) (xy 0.086614 0.20828) (xy 0.20828 0.086614)
						(xy 0.20828 -0.08636) (xy 0.08636 -0.20828) (xy -0.08636 -0.20828)
					)
					(width 0)
					(fill yes)
				)
			)
		)
		(zone
			(layer "B.Cu")
			(hatch none 0.5)
			(connect_pads
				(clearance 0)
			)
			(min_thickness 0.25)
			(keepout
				(tracks allowed)
				(vias not_allowed)
				(pads allowed)
				(copperpour not_allowed)
				(footprints allowed)
			)
			(placement
				(enabled no)
				(sheetname "")
			)
			(fill
				(thermal_gap 0.5)
				(thermal_bridge_width 0.5)
				(island_removal_mode 0)
			)
			(polygon
				(pts
					(xy 368.433858 -70.486524) (xy 368.433858 -70.105524) (xy 368.258598 -70.105524) (xy 368.258344 -70.486524)
				)
			)
		)
		(zone
			(layer "B.Cu")
			(hatch none 0.5)
			(connect_pads
				(clearance 0)
			)
			(min_thickness 0.25)
			(keepout
				(tracks not_allowed)
				(vias allowed)
				(pads allowed)
				(copperpour not_allowed)
				(footprints allowed)
			)
			(placement
				(enabled no)
				(sheetname "")
			)
			(fill
				(thermal_gap 0.5)
				(thermal_bridge_width 0.5)
				(island_removal_mode 0)
			)
			(polygon
				(pts
					(xy 368.433858 -70.486524) (xy 368.433858 -70.105524) (xy 368.258598 -70.105524) (xy 368.258344 -70.486524)
				)
			)
		)
	)
	(footprint ""
		(layer "B.Cu")
		(at 474.41866 -30.85592 90)
		(property "Reference" "C2T31"
			(at 0 0 90)
			(layer "B.SilkS")
			(hide yes)
			(effects
				(font
					(size 1.27 1.27)
				)
				(justify mirror)
			)
		)
		(property "Value" ""
			(at 0 0 90)
			(layer "B.Fab")
			(effects
				(font
					(size 1.27 1.27)
				)
				(justify mirror)
			)
		)
		(duplicate_pad_numbers_are_jumpers no)
		(fp_poly
			(pts
				(xy -0.3048 -0.1016) (xy -0.3048 0.9906) (xy 0.3048 0.9906) (xy 0.3048 -0.1016)
			)
			(stroke
				(width 0)
				(type default)
			)
			(fill no)
			(layer "B.CrtYd")
		)
		(fp_line
			(start 0.3048 -0.1016)
			(end 0.3048 0.9906)
			(stroke
				(width 0.1)
				(type default)
			)
			(layer "B.Fab")
		)
		(fp_line
			(start -0.3048 -0.1016)
			(end 0.3048 -0.1016)
			(stroke
				(width 0.1)
				(type default)
			)
			(layer "B.Fab")
		)
		(fp_line
			(start 0.3048 0.9906)
			(end -0.3048 0.9906)
			(stroke
				(width 0.1)
				(type default)
			)
			(layer "B.Fab")
		)
		(fp_line
			(start -0.3048 0.9906)
			(end -0.3048 -0.1016)
			(stroke
				(width 0.1)
				(type default)
			)
			(layer "B.Fab")
		)
		(pad "1" smd rect
			(at 0 0 270)
			(size 0.508 0.508)
			(layers "B.Cu" "B.Mask" "B.Paste")
			(net "P3V3_STBY_MNG_RGMII")
		)
		(pad "2" smd rect
			(at 0 0.889 270)
			(size 0.508 0.508)
			(layers "B.Cu" "B.Mask" "B.Paste")
			(net "GND")
		)
		(zone
			(layer "B.Cu")
			(hatch none 0.5)
			(connect_pads
				(clearance 0)
			)
			(min_thickness 0.25)
			(keepout
				(tracks allowed)
				(vias not_allowed)
				(pads allowed)
				(copperpour not_allowed)
				(footprints allowed)
			)
			(placement
				(enabled no)
				(sheetname "")
			)
			(fill
				(thermal_gap 0.5)
				(thermal_bridge_width 0.5)
				(island_removal_mode 0)
			)
			(polygon
				(pts
					(xy 474.67266 -31.10992) (xy 474.67266 -30.60192) (xy 475.05366 -30.60192) (xy 475.05366 -31.10992)
				)
			)
		)
		(zone
			(layer "B.Cu")
			(hatch none 0.5)
			(connect_pads
				(clearance 0)
			)
			(min_thickness 0.25)
			(keepout
				(tracks not_allowed)
				(vias allowed)
				(pads allowed)
				(copperpour not_allowed)
				(footprints allowed)
			)
			(placement
				(enabled no)
				(sheetname "")
			)
			(fill
				(thermal_gap 0.5)
				(thermal_bridge_width 0.5)
				(island_removal_mode 0)
			)
			(polygon
				(pts
					(xy 475.05366 -31.10992) (xy 475.05366 -30.60192) (xy 474.67266 -30.60192) (xy 474.67266 -31.10992)
				)
			)
		)
	)
	(footprint ""
		(layer "B.Cu")
		(at 426.9105 -11.176 90)
		(property "Reference" "R2U49"
			(at 0 0 90)
			(layer "B.SilkS")
			(hide yes)
			(effects
				(font
					(size 1.27 1.27)
				)
				(justify mirror)
			)
		)
		(property "Value" ""
			(at 0 0 90)
			(layer "B.Fab")
			(effects
				(font
					(size 1.27 1.27)
				)
				(justify mirror)
			)
		)
		(duplicate_pad_numbers_are_jumpers no)
		(fp_poly
			(pts
				(xy 0.2794 -0.1016) (xy -0.2794 -0.1016) (xy -0.2794 0.9906) (xy 0.2794 0.9906)
			)
			(stroke
				(width 0)
				(type default)
			)
			(fill no)
			(layer "B.CrtYd")
		)
		(fp_line
			(start 0.2794 -0.1016)
			(end 0.2794 0.9906)
			(stroke
				(width 0.1)
				(type default)
			)
			(layer "B.Fab")
		)
		(fp_line
			(start -0.2794 -0.1016)
			(end 0.2794 -0.1016)
			(stroke
				(width 0.1)
				(type default)
			)
			(layer "B.Fab")
		)
		(fp_line
			(start 0.2794 0.9906)
			(end -0.2794 0.9906)
			(stroke
				(width 0.1)
				(type default)
			)
			(layer "B.Fab")
		)
		(fp_line
			(start -0.2794 0.9906)
			(end -0.2794 -0.1016)
			(stroke
				(width 0.1)
				(type default)
			)
			(layer "B.Fab")
		)
		(pad "1" smd rect
			(at 0 0 270)
			(size 0.508 0.508)
			(layers "B.Cu" "B.Mask" "B.Paste")
			(net "H_CPU0_MEMABC_MEMHOT_G_PCH_N")
		)
		(pad "2" smd rect
			(at 0 0.889 270)
			(size 0.508 0.508)
			(layers "B.Cu" "B.Mask" "B.Paste")
			(net "H_CPU0_MEMABC_MEMHOT_LVT3_K_N")
		)
		(zone
			(layer "B.Cu")
			(hatch none 0.5)
			(connect_pads
				(clearance 0)
			)
			(min_thickness 0.25)
			(keepout
				(tracks allowed)
				(vias not_allowed)
				(pads allowed)
				(copperpour not_allowed)
				(footprints allowed)
			)
			(placement
				(enabled no)
				(sheetname "")
			)
			(fill
				(thermal_gap 0.5)
				(thermal_bridge_width 0.5)
				(island_removal_mode 0)
			)
			(polygon
				(pts
					(xy 427.1645 -11.43) (xy 427.1645 -10.922) (xy 427.5455 -10.922) (xy 427.5455 -11.43)
				)
			)
		)
		(zone
			(layer "B.Cu")
			(hatch none 0.5)
			(connect_pads
				(clearance 0)
			)
			(min_thickness 0.25)
			(keepout
				(tracks not_allowed)
				(vias allowed)
				(pads allowed)
				(copperpour not_allowed)
				(footprints allowed)
			)
			(placement
				(enabled no)
				(sheetname "")
			)
			(fill
				(thermal_gap 0.5)
				(thermal_bridge_width 0.5)
				(island_removal_mode 0)
			)
			(polygon
				(pts
					(xy 427.5455 -11.43) (xy 427.5455 -10.922) (xy 427.1645 -10.922) (xy 427.1645 -11.43)
				)
			)
		)
	)
	(footprint ""
		(layer "B.Cu")
		(at 416.9664 -26.035)
		(property "Reference" "R25W125"
			(at 0.8382 -0.67818 0)
			(unlocked yes)
			(layer "B.SilkS")
			(effects
				(font
					(size 0.4064 0.254)
					(thickness 0.1524)
				)
				(justify left mirror)
			)
		)
		(property "Value" ""
			(at 0 0 0)
			(layer "B.Fab")
			(effects
				(font
					(size 1.27 1.27)
				)
				(justify mirror)
			)
		)
		(duplicate_pad_numbers_are_jumpers no)
		(fp_poly
			(pts
				(xy 0.2794 -0.1016) (xy -0.2794 -0.1016) (xy -0.2794 0.9906) (xy 0.2794 0.9906)
			)
			(stroke
				(width 0)
				(type default)
			)
			(fill no)
			(layer "B.CrtYd")
		)
		(fp_line
			(start -0.2794 -0.1016)
			(end 0.2794 -0.1016)
			(stroke
				(width 0.1)
				(type default)
			)
			(layer "B.Fab")
		)
		(fp_line
			(start -0.2794 0.9906)
			(end -0.2794 -0.1016)
			(stroke
				(width 0.1)
				(type default)
			)
			(layer "B.Fab")
		)
		(fp_line
			(start 0.2794 -0.1016)
			(end 0.2794 0.9906)
			(stroke
				(width 0.1)
				(type default)
			)
			(layer "B.Fab")
		)
		(fp_line
			(start 0.2794 0.9906)
			(end -0.2794 0.9906)
			(stroke
				(width 0.1)
				(type default)
			)
			(layer "B.Fab")
		)
		(pad "1" smd rect
			(at 0 0 180)
			(size 0.508 0.508)
			(layers "B.Cu" "B.Mask" "B.Paste")
			(net "BMC_VGA_RED")
		)
		(pad "2" smd rect
			(at 0 0.889 180)
			(size 0.508 0.508)
			(layers "B.Cu" "B.Mask" "B.Paste")
			(net "GND")
		)
		(zone
			(layer "B.Cu")
			(hatch none 0.5)
			(connect_pads
				(clearance 0)
			)
			(min_thickness 0.25)
			(keepout
				(tracks allowed)
				(vias not_allowed)
				(pads allowed)
				(copperpour not_allowed)
				(footprints allowed)
			)
			(placement
				(enabled no)
				(sheetname "")
			)
			(fill
				(thermal_gap 0.5)
				(thermal_bridge_width 0.5)
				(island_removal_mode 0)
			)
			(polygon
				(pts
					(xy 417.2204 -25.781) (xy 416.7124 -25.781) (xy 416.7124 -25.4) (xy 417.2204 -25.4)
				)
			)
		)
		(zone
			(layer "B.Cu")
			(hatch none 0.5)
			(connect_pads
				(clearance 0)
			)
			(min_thickness 0.25)
			(keepout
				(tracks not_allowed)
				(vias allowed)
				(pads allowed)
				(copperpour not_allowed)
				(footprints allowed)
			)
			(placement
				(enabled no)
				(sheetname "")
			)
			(fill
				(thermal_gap 0.5)
				(thermal_bridge_width 0.5)
				(island_removal_mode 0)
			)
			(polygon
				(pts
					(xy 417.2204 -25.4) (xy 416.7124 -25.4) (xy 416.7124 -25.781) (xy 417.2204 -25.781)
				)
			)
		)
	)
)
